# BASEBOARD_FAB2 (Tioga Pass) — schematic netlist excerpt (pin names and nets, part order shuffled) for the footprints in the layout excerpt that follows; sources: Cadence DE-HDL packaged netlist, KiCad conversion of Wiwynn_Tioga_Pass_MB.brd

C3D25  CAP_A  22.0UF 4V 20% X6S  pkg 0603V  page 225 : A = PVDDQ_GHJ ; B = GND

(kicad_pcb
	(version 20260206)
	(generator "pcbnew")
	(generator_version "10.0")
	(general
		(thickness 1.6)
		(legacy_teardrops no)
	)
	(paper "A4")
	(title_block
		(title "Wiwynn_Tioga_Pass_MB.brd")
		(comment 1 "Tioga Pass / footprints 635-635 of 4770")
	)
	(layers
		(0 "F.Cu" signal "TOP")
		(4 "In1.Cu" signal "L2GND")
		(6 "In2.Cu" signal "L3")
		(8 "In3.Cu" signal "L4GND")
		(10 "In4.Cu" signal "L5")
		(12 "In5.Cu" signal "L6GND")
		(14 "In6.Cu" signal "L7VCC")
		(16 "In7.Cu" signal "L8VCC")
		(18 "In8.Cu" signal "L9GND")
		(20 "In9.Cu" signal "L10")
		(22 "In10.Cu" signal "L11GND")
		(24 "In11.Cu" signal "L12")
		(26 "In12.Cu" signal "L13GND")
		(2 "B.Cu" signal "BOTTOM")
		(9 "F.Adhes" user "F.Adhesive")
		(11 "B.Adhes" user "B.Adhesive")
		(13 "F.Paste" user "Package Geometry/Pastemask Top")
		(15 "B.Paste" user "Package Geometry/Pastemask Bottom")
		(5 "F.SilkS" user "Ref Des/Silkscreen Top")
		(7 "B.SilkS" user "Ref Des/Silkscreen Bottom")
		(1 "F.Mask" user "Board Geometry/Soldermask Top")
		(3 "B.Mask" user "Board Geometry/Soldermask Bottom")
		(17 "Dwgs.User" user "User.Drawings")
		(19 "Cmts.User" user "User.Comments")
		(21 "Eco1.User" user "User.Eco1")
		(23 "Eco2.User" user "User.Eco2")
		(25 "Edge.Cuts" user "Board Geometry/Outline")
		(27 "Margin" user)
		(31 "F.CrtYd" user "Package Geometry/Place Bound Top")
		(29 "B.CrtYd" user "Package Geometry/Place Bound Bottom")
		(35 "F.Fab" user "Ref Des/Assembly Top")
		(33 "B.Fab" user "Ref Des/Assembly Bottom")
	)
	(footprint ""
		(layer "F.Cu")
		(at 107.134406 -68.365116 180)
		(property "Reference" "C3D25"
			(at 0 0 180)
			(layer "F.SilkS")
			(hide yes)
			(effects
				(font
					(size 1.27 1.27)
				)
			)
		)
		(property "Value" ""
			(at 0 0 180)
			(layer "F.Fab")
			(effects
				(font
					(size 1.27 1.27)
				)
			)
		)
		(duplicate_pad_numbers_are_jumpers no)
		(fp_poly
			(pts
				(xy -0.4953 -0.2032) (xy 0.4953 -0.2032) (xy 0.4953 1.6002) (xy -0.4953 1.6002)
			)
			(stroke
				(width 0)
				(type default)
			)
			(fill no)
			(layer "F.CrtYd")
		)
		(fp_line
			(start 0.4953 1.6002)
			(end -0.4953 1.6002)
			(stroke
				(width 0.1)
				(type default)
			)
			(layer "F.Fab")
		)
		(fp_line
			(start 0.4953 -0.2032)
			(end 0.4953 1.6002)
			(stroke
				(width 0.1)
				(type default)
			)
			(layer "F.Fab")
		)
		(fp_line
			(start -0.4953 1.6002)
			(end -0.4953 -0.2032)
			(stroke
				(width 0.1)
				(type default)
			)
			(layer "F.Fab")
		)
		(fp_line
			(start -0.4953 -0.2032)
			(end 0.4953 -0.2032)
			(stroke
				(width 0.1)
				(type default)
			)
			(layer "F.Fab")
		)
		(pad "1" smd rect
			(at 0 0 180)
			(size 0.762 0.889)
			(layers "F.Cu" "F.Mask" "F.Paste")
			(net "PVDDQ_GHJ")
		)
		(pad "2" smd rect
			(at 0 1.397 180)
			(size 0.762 0.889)
			(layers "F.Cu" "F.Mask" "F.Paste")
			(net "GND")
		)
		(zone
			(layer "F.Cu")
			(hatch none 0.5)
			(connect_pads
				(clearance 0)
			)
			(min_thickness 0.25)
			(keepout
				(tracks not_allowed)
				(vias allowed)
				(pads allowed)
				(copperpour not_allowed)
				(footprints allowed)
			)
			(placement
				(enabled no)
				(sheetname "")
			)
			(fill
				(thermal_gap 0.5)
				(thermal_bridge_width 0.5)
				(island_removal_mode 0)
			)
			(polygon
				(pts
					(xy 107.515406 -68.809616) (xy 106.753406 -68.809616) (xy 106.753406 -69.317616) (xy 107.515406 -69.317616)
				)
			)
		)
	)
)
